# T6G (Grand Teton) — schematic netlist excerpt (pin names and nets, part order shuffled) for the footprints in the layout excerpt that follows; sources: Cadence DE-HDL packaged netlist, KiCad conversion of 04192023_DAF0TMB3IC0_F0TG_MB_C_brd_V02_OCP.brd

R4168  Q_RES  100K 1% CHIP  pkg 0402LF  page 124 : A = P3V3_AUX ; B = GPU_3V3IO_RSVD4_ISO
R8178  Q_RES  33 5% CHIP  pkg 0402LF  page 210 : A = PWRGD_PVDDCR_CPU0_P1 ; B = PWRGD_PVDDCR_CPU0_P1_R

(kicad_pcb
	(version 20260206)
	(generator "pcbnew")
	(generator_version "10.0")
	(general
		(thickness 1.6)
		(legacy_teardrops no)
	)
	(paper "A4")
	(title_block
		(title "04192023_DAF0TMB3IC0_F0TG_MB_C_brd_V02_OCP.brd")
		(comment 1 "Grand Teton / footprints 394-395 of 8354")
	)
	(layers
		(0 "F.Cu" signal "TOP")
		(4 "In1.Cu" signal "GND")
		(6 "In2.Cu" signal "IN1")
		(8 "In3.Cu" signal "GND1")
		(10 "In4.Cu" signal "IN2")
		(12 "In5.Cu" signal "GND2")
		(14 "In6.Cu" signal "IN3")
		(16 "In7.Cu" signal "GND3")
		(18 "In8.Cu" signal "VCC")
		(20 "In9.Cu" signal "VCC1")
		(22 "In10.Cu" signal "GND4")
		(24 "In11.Cu" signal "IN4")
		(26 "In12.Cu" signal "GND5")
		(28 "In13.Cu" signal "IN5")
		(30 "In14.Cu" signal "GND6")
		(32 "In15.Cu" signal "IN6")
		(34 "In16.Cu" signal "GND7")
		(2 "B.Cu" signal "BOTTOM")
		(9 "F.Adhes" user "F.Adhesive")
		(11 "B.Adhes" user "B.Adhesive")
		(13 "F.Paste" user "Package Geometry/Pastemask Top")
		(15 "B.Paste" user "Package Geometry/Pastemask Bottom")
		(5 "F.SilkS" user "Ref Des/Silkscreen Top")
		(7 "B.SilkS" user "Ref Des/Silkscreen Bottom")
		(1 "F.Mask" user "Board Geometry/Soldermask Top")
		(3 "B.Mask" user "Board Geometry/Soldermask Bottom")
		(17 "Dwgs.User" user "User.Drawings")
		(19 "Cmts.User" user "User.Comments")
		(21 "Eco1.User" user "User.Eco1")
		(23 "Eco2.User" user "User.Eco2")
		(25 "Edge.Cuts" user "Board Geometry/Outline")
		(27 "Margin" user)
		(31 "F.CrtYd" user "Package Geometry/Place Bound Top")
		(29 "B.CrtYd" user "Package Geometry/Place Bound Bottom")
		(35 "F.Fab" user "Ref Des/Assembly Top")
		(33 "B.Fab" user "Ref Des/Assembly Bottom")
	)
	(footprint ""
		(layer "F.Cu")
		(at 90.825828 -141.42466 90)
		(property "Reference" "R8178"
			(at 0 0 90)
			(layer "F.SilkS")
			(hide yes)
			(effects
				(font
					(size 1.27 1.27)
				)
			)
		)
		(property "Value" ""
			(at 0 0 90)
			(layer "F.Fab")
			(effects
				(font
					(size 1.27 1.27)
				)
			)
		)
		(duplicate_pad_numbers_are_jumpers no)
		(fp_line
			(start 0.7874 -0.4064)
			(end 0.7874 0.4064)
			(stroke
				(width 0.1524)
				(type default)
			)
			(layer "F.SilkS")
		)
		(fp_line
			(start -0.7874 -0.4064)
			(end 0.7874 -0.4064)
			(stroke
				(width 0.1524)
				(type default)
			)
			(layer "F.SilkS")
		)
		(fp_line
			(start 0.7874 0.4064)
			(end -0.7874 0.4064)
			(stroke
				(width 0.1524)
				(type default)
			)
			(layer "F.SilkS")
		)
		(fp_line
			(start -0.7874 0.4064)
			(end -0.7874 -0.4064)
			(stroke
				(width 0.1524)
				(type default)
			)
			(layer "F.SilkS")
		)
		(fp_line
			(start -0.12065 -0.305054)
			(end -0.12065 -0.2794)
			(stroke
				(width 0.1)
				(type default)
			)
			(layer "F.Fab")
		)
		(fp_line
			(start -0.67945 -0.305054)
			(end -0.12065 -0.305054)
			(stroke
				(width 0.1)
				(type default)
			)
			(layer "F.Fab")
		)
		(fp_line
			(start 0.67945 -0.3048)
			(end 0.67945 0.3048)
			(stroke
				(width 0.1)
				(type default)
			)
			(layer "F.Fab")
		)
		(fp_line
			(start 0.12065 -0.3048)
			(end 0.67945 -0.3048)
			(stroke
				(width 0.1)
				(type default)
			)
			(layer "F.Fab")
		)
		(fp_line
			(start 0.12065 -0.2794)
			(end 0.12065 -0.3048)
			(stroke
				(width 0.1)
				(type default)
			)
			(layer "F.Fab")
		)
		(fp_line
			(start -0.12065 -0.2794)
			(end 0.12065 -0.2794)
			(stroke
				(width 0.1)
				(type default)
			)
			(layer "F.Fab")
		)
		(fp_line
			(start 0.120396 0.2794)
			(end -0.12065 0.2794)
			(stroke
				(width 0.1)
				(type default)
			)
			(layer "F.Fab")
		)
		(fp_line
			(start -0.12065 0.2794)
			(end -0.12065 0.3048)
			(stroke
				(width 0.1)
				(type default)
			)
			(layer "F.Fab")
		)
		(fp_line
			(start 0.67945 0.3048)
			(end 0.120396 0.3048)
			(stroke
				(width 0.1)
				(type default)
			)
			(layer "F.Fab")
		)
		(fp_line
			(start 0.120396 0.3048)
			(end 0.120396 0.2794)
			(stroke
				(width 0.1)
				(type default)
			)
			(layer "F.Fab")
		)
		(fp_line
			(start -0.12065 0.3048)
			(end -0.67945 0.3048)
			(stroke
				(width 0.1)
				(type default)
			)
			(layer "F.Fab")
		)
		(fp_line
			(start -0.67945 0.3048)
			(end -0.67945 -0.305054)
			(stroke
				(width 0.1)
				(type default)
			)
			(layer "F.Fab")
		)
		(pad "1" smd circle
			(at -0.40005 0 90)
			(size 0 0)
			(layers "F.Cu" "F.Mask" "F.Paste")
			(net "PWRGD_PVDDCR_CPU0_P1")
		)
		(pad "2" smd circle
			(at 0.40005 0 90)
			(size 0 0)
			(layers "F.Cu" "F.Mask" "F.Paste")
			(net "PWRGD_PVDDCR_CPU0_P1_R")
		)
	)
	(footprint ""
		(layer "F.Cu")
		(at 438.056782 -437.34736 90)
		(property "Reference" "R4168"
			(at 0 0 90)
			(layer "F.SilkS")
			(hide yes)
			(effects
				(font
					(size 1.27 1.27)
				)
			)
		)
		(property "Value" ""
			(at 0 0 90)
			(layer "F.Fab")
			(effects
				(font
					(size 1.27 1.27)
				)
			)
		)
		(duplicate_pad_numbers_are_jumpers no)
		(fp_line
			(start 0.7874 -0.4064)
			(end 0.7874 0.4064)
			(stroke
				(width 0.1524)
				(type default)
			)
			(layer "F.SilkS")
		)
		(fp_line
			(start -0.7874 -0.4064)
			(end 0.7874 -0.4064)
			(stroke
				(width 0.1524)
				(type default)
			)
			(layer "F.SilkS")
		)
		(fp_line
			(start 0.7874 0.4064)
			(end -0.7874 0.4064)
			(stroke
				(width 0.1524)
				(type default)
			)
			(layer "F.SilkS")
		)
		(fp_line
			(start -0.7874 0.4064)
			(end -0.7874 -0.4064)
			(stroke
				(width 0.1524)
				(type default)
			)
			(layer "F.SilkS")
		)
		(fp_line
			(start -0.12065 -0.305054)
			(end -0.12065 -0.2794)
			(stroke
				(width 0.1)
				(type default)
			)
			(layer "F.Fab")
		)
		(fp_line
			(start -0.67945 -0.305054)
			(end -0.12065 -0.305054)
			(stroke
				(width 0.1)
				(type default)
			)
			(layer "F.Fab")
		)
		(fp_line
			(start 0.67945 -0.3048)
			(end 0.67945 0.3048)
			(stroke
				(width 0.1)
				(type default)
			)
			(layer "F.Fab")
		)
		(fp_line
			(start 0.12065 -0.3048)
			(end 0.67945 -0.3048)
			(stroke
				(width 0.1)
				(type default)
			)
			(layer "F.Fab")
		)
		(fp_line
			(start 0.12065 -0.2794)
			(end 0.12065 -0.3048)
			(stroke
				(width 0.1)
				(type default)
			)
			(layer "F.Fab")
		)
		(fp_line
			(start -0.12065 -0.2794)
			(end 0.12065 -0.2794)
			(stroke
				(width 0.1)
				(type default)
			)
			(layer "F.Fab")
		)
		(fp_line
			(start 0.120396 0.2794)
			(end -0.12065 0.2794)
			(stroke
				(width 0.1)
				(type default)
			)
			(layer "F.Fab")
		)
		(fp_line
			(start -0.12065 0.2794)
			(end -0.12065 0.3048)
			(stroke
				(width 0.1)
				(type default)
			)
			(layer "F.Fab")
		)
		(fp_line
			(start 0.67945 0.3048)
			(end 0.120396 0.3048)
			(stroke
				(width 0.1)
				(type default)
			)
			(layer "F.Fab")
		)
		(fp_line
			(start 0.120396 0.3048)
			(end 0.120396 0.2794)
			(stroke
				(width 0.1)
				(type default)
			)
			(layer "F.Fab")
		)
		(fp_line
			(start -0.12065 0.3048)
			(end -0.67945 0.3048)
			(stroke
				(width 0.1)
				(type default)
			)
			(layer "F.Fab")
		)
		(fp_line
			(start -0.67945 0.3048)
			(end -0.67945 -0.305054)
			(stroke
				(width 0.1)
				(type default)
			)
			(layer "F.Fab")
		)
		(pad "1" smd circle
			(at -0.40005 0 90)
			(size 0 0)
			(layers "F.Cu" "F.Mask" "F.Paste")
			(net "P3V3_AUX")
		)
		(pad "2" smd circle
			(at 0.40005 0 90)
			(size 0 0)
			(layers "F.Cu" "F.Mask" "F.Paste")
			(net "GPU_3V3IO_RSVD4_ISO")
		)
	)
)
